# BASEBOARD_FAB2 (Tioga Pass) — schematic netlist excerpt (pin names and nets, part order shuffled) for the footprints in the layout excerpt that follows; sources: Cadence DE-HDL packaged netlist, KiCad conversion of Wiwynn_Tioga_Pass_MB.brd

C2M8  CAP_A  1.0UF 6.3V 10% X6S  pkg 0402V  page 127 : A = P1V05_PCH_STBY ; B = GND
R3W10  RES  49.9 1% EMPTY  pkg 0402  page 92 : A = PVCCIO_CPU0 ; B = P0V7_GTL2104_VREF_1
R6W38  RES  20.0K 1% CHIP  pkg 0402  page 176 : A = DEBUG_CARD2_PRSNT ; B = GND

(kicad_pcb
	(version 20260206)
	(generator "pcbnew")
	(generator_version "10.0")
	(general
		(thickness 1.6)
		(legacy_teardrops no)
	)
	(paper "A4")
	(title_block
		(title "Wiwynn_Tioga_Pass_MB.brd")
		(comment 1 "Tioga Pass / footprints 4432-4434 of 4770")
	)
	(layers
		(0 "F.Cu" signal "TOP")
		(4 "In1.Cu" signal "L2GND")
		(6 "In2.Cu" signal "L3")
		(8 "In3.Cu" signal "L4GND")
		(10 "In4.Cu" signal "L5")
		(12 "In5.Cu" signal "L6GND")
		(14 "In6.Cu" signal "L7VCC")
		(16 "In7.Cu" signal "L8VCC")
		(18 "In8.Cu" signal "L9GND")
		(20 "In9.Cu" signal "L10")
		(22 "In10.Cu" signal "L11GND")
		(24 "In11.Cu" signal "L12")
		(26 "In12.Cu" signal "L13GND")
		(2 "B.Cu" signal "BOTTOM")
		(9 "F.Adhes" user "F.Adhesive")
		(11 "B.Adhes" user "B.Adhesive")
		(13 "F.Paste" user "Package Geometry/Pastemask Top")
		(15 "B.Paste" user "Package Geometry/Pastemask Bottom")
		(5 "F.SilkS" user "Ref Des/Silkscreen Top")
		(7 "B.SilkS" user "Ref Des/Silkscreen Bottom")
		(1 "F.Mask" user "Board Geometry/Soldermask Top")
		(3 "B.Mask" user "Board Geometry/Soldermask Bottom")
		(17 "Dwgs.User" user "User.Drawings")
		(19 "Cmts.User" user "User.Comments")
		(21 "Eco1.User" user "User.Eco1")
		(23 "Eco2.User" user "User.Eco2")
		(25 "Edge.Cuts" user "Board Geometry/Outline")
		(27 "Margin" user)
		(31 "F.CrtYd" user "Package Geometry/Place Bound Top")
		(29 "B.CrtYd" user "Package Geometry/Place Bound Bottom")
		(35 "F.Fab" user "Ref Des/Assembly Top")
		(33 "B.Fab" user "Ref Des/Assembly Bottom")
	)
	(footprint ""
		(layer "B.Cu")
		(at 375.1072 -57.785 180)
		(property "Reference" "R3W10"
			(at 0.8382 -0.67818 180)
			(unlocked yes)
			(layer "B.SilkS")
			(effects
				(font
					(size 0.4064 0.254)
					(thickness 0.1524)
				)
				(justify left mirror)
			)
		)
		(property "Value" ""
			(at 0 0 0)
			(layer "B.Fab")
			(effects
				(font
					(size 1.27 1.27)
				)
				(justify mirror)
			)
		)
		(duplicate_pad_numbers_are_jumpers no)
		(fp_poly
			(pts
				(xy 0.2794 -0.1016) (xy -0.2794 -0.1016) (xy -0.2794 0.9906) (xy 0.2794 0.9906)
			)
			(stroke
				(width 0)
				(type default)
			)
			(fill no)
			(layer "B.CrtYd")
		)
		(fp_line
			(start 0.2794 0.9906)
			(end -0.2794 0.9906)
			(stroke
				(width 0.1)
				(type default)
			)
			(layer "B.Fab")
		)
		(fp_line
			(start 0.2794 -0.1016)
			(end 0.2794 0.9906)
			(stroke
				(width 0.1)
				(type default)
			)
			(layer "B.Fab")
		)
		(fp_line
			(start -0.2794 0.9906)
			(end -0.2794 -0.1016)
			(stroke
				(width 0.1)
				(type default)
			)
			(layer "B.Fab")
		)
		(fp_line
			(start -0.2794 -0.1016)
			(end 0.2794 -0.1016)
			(stroke
				(width 0.1)
				(type default)
			)
			(layer "B.Fab")
		)
		(pad "1" smd rect
			(at 0 0)
			(size 0.508 0.508)
			(layers "B.Cu" "B.Mask" "B.Paste")
			(net "PVCCIO_CPU0")
		)
		(pad "2" smd rect
			(at 0 0.889)
			(size 0.508 0.508)
			(layers "B.Cu" "B.Mask" "B.Paste")
			(net "P0V7_GTL2104_VREF_1")
		)
		(zone
			(layer "B.Cu")
			(hatch none 0.5)
			(connect_pads
				(clearance 0)
			)
			(min_thickness 0.25)
			(keepout
				(tracks not_allowed)
				(vias allowed)
				(pads allowed)
				(copperpour not_allowed)
				(footprints allowed)
			)
			(placement
				(enabled no)
				(sheetname "")
			)
			(fill
				(thermal_gap 0.5)
				(thermal_bridge_width 0.5)
				(island_removal_mode 0)
			)
			(polygon
				(pts
					(xy 374.8532 -58.42) (xy 375.3612 -58.42) (xy 375.3612 -58.039) (xy 374.8532 -58.039)
				)
			)
		)
		(zone
			(layer "B.Cu")
			(hatch none 0.5)
			(connect_pads
				(clearance 0)
			)
			(min_thickness 0.25)
			(keepout
				(tracks allowed)
				(vias not_allowed)
				(pads allowed)
				(copperpour not_allowed)
				(footprints allowed)
			)
			(placement
				(enabled no)
				(sheetname "")
			)
			(fill
				(thermal_gap 0.5)
				(thermal_bridge_width 0.5)
				(island_removal_mode 0)
			)
			(polygon
				(pts
					(xy 374.8532 -58.039) (xy 375.3612 -58.039) (xy 375.3612 -58.42) (xy 374.8532 -58.42)
				)
			)
		)
	)
	(footprint ""
		(layer "B.Cu")
		(at 500.1514 -140.8684)
		(property "Reference" "R6W38"
			(at 0.8382 -0.67818 0)
			(unlocked yes)
			(layer "B.SilkS")
			(effects
				(font
					(size 0.4064 0.254)
					(thickness 0.1524)
				)
				(justify left mirror)
			)
		)
		(property "Value" ""
			(at 0 0 0)
			(layer "B.Fab")
			(effects
				(font
					(size 1.27 1.27)
				)
				(justify mirror)
			)
		)
		(duplicate_pad_numbers_are_jumpers no)
		(fp_poly
			(pts
				(xy 0.2794 -0.1016) (xy -0.2794 -0.1016) (xy -0.2794 0.9906) (xy 0.2794 0.9906)
			)
			(stroke
				(width 0)
				(type default)
			)
			(fill no)
			(layer "B.CrtYd")
		)
		(fp_line
			(start -0.2794 -0.1016)
			(end 0.2794 -0.1016)
			(stroke
				(width 0.1)
				(type default)
			)
			(layer "B.Fab")
		)
		(fp_line
			(start -0.2794 0.9906)
			(end -0.2794 -0.1016)
			(stroke
				(width 0.1)
				(type default)
			)
			(layer "B.Fab")
		)
		(fp_line
			(start 0.2794 -0.1016)
			(end 0.2794 0.9906)
			(stroke
				(width 0.1)
				(type default)
			)
			(layer "B.Fab")
		)
		(fp_line
			(start 0.2794 0.9906)
			(end -0.2794 0.9906)
			(stroke
				(width 0.1)
				(type default)
			)
			(layer "B.Fab")
		)
		(pad "1" smd rect
			(at 0 0 180)
			(size 0.508 0.508)
			(layers "B.Cu" "B.Mask" "B.Paste")
			(net "DEBUG_CARD2_PRSNT")
		)
		(pad "2" smd rect
			(at 0 0.889 180)
			(size 0.508 0.508)
			(layers "B.Cu" "B.Mask" "B.Paste")
			(net "GND")
		)
		(zone
			(layer "B.Cu")
			(hatch none 0.5)
			(connect_pads
				(clearance 0)
			)
			(min_thickness 0.25)
			(keepout
				(tracks allowed)
				(vias not_allowed)
				(pads allowed)
				(copperpour not_allowed)
				(footprints allowed)
			)
			(placement
				(enabled no)
				(sheetname "")
			)
			(fill
				(thermal_gap 0.5)
				(thermal_bridge_width 0.5)
				(island_removal_mode 0)
			)
			(polygon
				(pts
					(xy 500.4054 -140.6144) (xy 499.8974 -140.6144) (xy 499.8974 -140.2334) (xy 500.4054 -140.2334)
				)
			)
		)
		(zone
			(layer "B.Cu")
			(hatch none 0.5)
			(connect_pads
				(clearance 0)
			)
			(min_thickness 0.25)
			(keepout
				(tracks not_allowed)
				(vias allowed)
				(pads allowed)
				(copperpour not_allowed)
				(footprints allowed)
			)
			(placement
				(enabled no)
				(sheetname "")
			)
			(fill
				(thermal_gap 0.5)
				(thermal_bridge_width 0.5)
				(island_removal_mode 0)
			)
			(polygon
				(pts
					(xy 500.4054 -140.2334) (xy 499.8974 -140.2334) (xy 499.8974 -140.6144) (xy 500.4054 -140.6144)
				)
			)
		)
	)
	(footprint ""
		(layer "B.Cu")
		(at 409.23845 -122.216418)
		(property "Reference" "C2M8"
			(at 0 0 0)
			(layer "B.SilkS")
			(hide yes)
			(effects
				(font
					(size 1.27 1.27)
				)
				(justify mirror)
			)
		)
		(property "Value" ""
			(at 0 0 0)
			(layer "B.Fab")
			(effects
				(font
					(size 1.27 1.27)
				)
				(justify mirror)
			)
		)
		(duplicate_pad_numbers_are_jumpers no)
		(fp_poly
			(pts
				(xy -0.3048 -0.1016) (xy -0.3048 0.9906) (xy 0.3048 0.9906) (xy 0.3048 -0.1016)
			)
			(stroke
				(width 0)
				(type default)
			)
			(fill no)
			(layer "B.CrtYd")
		)
		(fp_line
			(start -0.3048 -0.1016)
			(end 0.3048 -0.1016)
			(stroke
				(width 0.1)
				(type default)
			)
			(layer "B.Fab")
		)
		(fp_line
			(start -0.3048 0.9906)
			(end -0.3048 -0.1016)
			(stroke
				(width 0.1)
				(type default)
			)
			(layer "B.Fab")
		)
		(fp_line
			(start 0.3048 -0.1016)
			(end 0.3048 0.9906)
			(stroke
				(width 0.1)
				(type default)
			)
			(layer "B.Fab")
		)
		(fp_line
			(start 0.3048 0.9906)
			(end -0.3048 0.9906)
			(stroke
				(width 0.1)
				(type default)
			)
			(layer "B.Fab")
		)
		(pad "1" smd rect
			(at 0 0 180)
			(size 0.508 0.508)
			(layers "B.Cu" "B.Mask" "B.Paste")
			(net "P1V05_PCH_STBY")
		)
		(pad "2" smd rect
			(at 0 0.889 180)
			(size 0.508 0.508)
			(layers "B.Cu" "B.Mask" "B.Paste")
			(net "GND")
		)
		(zone
			(layer "B.Cu")
			(hatch none 0.5)
			(connect_pads
				(clearance 0)
			)
			(min_thickness 0.25)
			(keepout
				(tracks allowed)
				(vias not_allowed)
				(pads allowed)
				(copperpour not_allowed)
				(footprints allowed)
			)
			(placement
				(enabled no)
				(sheetname "")
			)
			(fill
				(thermal_gap 0.5)
				(thermal_bridge_width 0.5)
				(island_removal_mode 0)
			)
			(polygon
				(pts
					(xy 409.49245 -121.962418) (xy 408.98445 -121.962418) (xy 408.98445 -121.581418) (xy 409.49245 -121.581418)
				)
			)
		)
		(zone
			(layer "B.Cu")
			(hatch none 0.5)
			(connect_pads
				(clearance 0)
			)
			(min_thickness 0.25)
			(keepout
				(tracks not_allowed)
				(vias allowed)
				(pads allowed)
				(copperpour not_allowed)
				(footprints allowed)
			)
			(placement
				(enabled no)
				(sheetname "")
			)
			(fill
				(thermal_gap 0.5)
				(thermal_bridge_width 0.5)
				(island_removal_mode 0)
			)
			(polygon
				(pts
					(xy 409.49245 -121.581418) (xy 408.98445 -121.581418) (xy 408.98445 -121.962418) (xy 409.49245 -121.962418)
				)
			)
		)
	)
)
